# SDI-MIPI Bridge — KiCad custom design rules (.kicad_dru)
(version 1)

#calculated as 100Ohm diff @ 55OHM SE 
(rule "100OHM_diff_outer" 
	(constraint track_width (opt 0.1mm))
	(constraint diff_pair_gap (opt 0.1mm))
	(constraint clearance (opt 0.1mm))
	(condition "(A.NetClass == '100Ohm-diff')")
	(layer outer)
)

(rule "100OHM_diff_inner @ 55Ohm SE" 
	(constraint track_width (opt 0.127mm))
	(constraint diff_pair_gap (opt 0.25mm))
	(constraint clearance (opt 0.127mm))
	(condition "(A.NetClass == '100Ohm-diff')")
	(layer inner)
)


